(kicad_pcb
	(version 20260206)
	(generator "pcbnew")
	(generator_version "10.0")
	(general
		(thickness 1.6)
		(legacy_teardrops no)
	)
	(paper "A4")
	(title_block
		(title "04192023_DAF0TMB3IC0_F0TG_MB_C_brd_V02_OCP.brd")
		(comment 1 "Grand Teton / footprint 2783 of 8354 (U26), pads 4003-4112 of 6102")
	)
	(layers
		(0 "F.Cu" signal "TOP")
		(4 "In1.Cu" signal "GND")
		(6 "In2.Cu" signal "IN1")
		(8 "In3.Cu" signal "GND1")
		(10 "In4.Cu" signal "IN2")
		(12 "In5.Cu" signal "GND2")
		(14 "In6.Cu" signal "IN3")
		(16 "In7.Cu" signal "GND3")
		(18 "In8.Cu" signal "VCC")
		(20 "In9.Cu" signal "VCC1")
		(22 "In10.Cu" signal "GND4")
		(24 "In11.Cu" signal "IN4")
		(26 "In12.Cu" signal "GND5")
		(28 "In13.Cu" signal "IN5")
		(30 "In14.Cu" signal "GND6")
		(32 "In15.Cu" signal "IN6")
		(34 "In16.Cu" signal "GND7")
		(2 "B.Cu" signal "BOTTOM")
		(9 "F.Adhes" user "F.Adhesive")
		(11 "B.Adhes" user "B.Adhesive")
		(13 "F.Paste" user "Package Geometry/Pastemask Top")
		(15 "B.Paste" user "Package Geometry/Pastemask Bottom")
		(5 "F.SilkS" user "Ref Des/Silkscreen Top")
		(7 "B.SilkS" user "Ref Des/Silkscreen Bottom")
		(1 "F.Mask" user "Board Geometry/Soldermask Top")
		(3 "B.Mask" user "Board Geometry/Soldermask Bottom")
		(17 "Dwgs.User" user "User.Drawings")
		(19 "Cmts.User" user "User.Comments")
		(21 "Eco1.User" user "User.Eco1")
		(23 "Eco2.User" user "User.Eco2")
		(25 "Edge.Cuts" user "Board Geometry/Outline")
		(27 "Margin" user)
		(31 "F.CrtYd" user "Package Geometry/Place Bound Top")
		(29 "B.CrtYd" user "Package Geometry/Place Bound Bottom")
		(35 "F.Fab" user "Ref Des/Assembly Top")
		(33 "B.Fab" user "Ref Des/Assembly Bottom")
	)
	(footprint ""
		(layer "F.Cu")
		(at 111.927894 -258.880356 180)
		(property "Reference" "U26"
			(at -45.05579 -61.794136 0)
			(unlocked yes)
			(layer "F.SilkS")
			(effects
				(font
					(size 0.7874 0.5842)
					(thickness 0.1524)
				)
			)
		)
		(property "Value" ""
			(at 0 0 180)
			(layer "F.Fab")
			(effects
				(font
					(size 1.27 1.27)
				)
			)
		)
		(duplicate_pad_numbers_are_jumpers no)
		(pad "CU46" smd circle
			(at 6.89991 27.090116 180)
			(size 0.450088 0.450088)
			(layers "F.Cu" "F.Mask" "F.Paste")
			(net "P5E_CPU1_P0_TX_DN<8>")
		)
		(pad "CU47" smd circle
			(at 7.839964 27.090116 180)
			(size 0.450088 0.450088)
			(layers "F.Cu" "F.Mask" "F.Paste")
			(net "P5E_CPU1_P0_TX_DP<8>")
		)
		(pad "CU48" smd circle
			(at 8.780018 27.090116 180)
			(size 0.450088 0.450088)
			(layers "F.Cu" "F.Mask" "F.Paste")
			(net "GND")
		)
		(pad "CU49" smd circle
			(at 9.720072 27.090116 180)
			(size 0.450088 0.450088)
			(layers "F.Cu" "F.Mask" "F.Paste")
			(net "P5E_CPU1_P0_TX_DN<5>")
		)
		(pad "CU50" smd circle
			(at 10.659872 27.090116 180)
			(size 0.450088 0.450088)
			(layers "F.Cu" "F.Mask" "F.Paste")
			(net "P5E_CPU1_P0_TX_DP<5>")
		)
		(pad "CU51" smd circle
			(at 11.599926 27.090116 180)
			(size 0.450088 0.450088)
			(layers "F.Cu" "F.Mask" "F.Paste")
			(net "GND")
		)
		(pad "CU52" smd circle
			(at 12.53998 27.090116 180)
			(size 0.450088 0.450088)
			(layers "F.Cu" "F.Mask" "F.Paste")
			(net "P5E_CPU1_P1_TX_DN<0>")
		)
		(pad "CU53" smd circle
			(at 13.480034 27.090116 180)
			(size 0.450088 0.450088)
			(layers "F.Cu" "F.Mask" "F.Paste")
			(net "P5E_CPU1_P1_TX_DP<0>")
		)
		(pad "CU54" smd circle
			(at 14.420088 27.090116 180)
			(size 0.450088 0.450088)
			(layers "F.Cu" "F.Mask" "F.Paste")
			(net "GND")
		)
		(pad "CU55" smd circle
			(at 15.359888 27.090116 180)
			(size 0.450088 0.450088)
			(layers "F.Cu" "F.Mask" "F.Paste")
			(net "M_C_CPU1_SB_DQS_DN<7>")
		)
		(pad "CU56" smd circle
			(at 16.299942 27.090116 180)
			(size 0.450088 0.450088)
			(layers "F.Cu" "F.Mask" "F.Paste")
			(net "GND")
		)
		(pad "CU57" smd circle
			(at 17.239996 27.090116 180)
			(size 0.450088 0.450088)
			(layers "F.Cu" "F.Mask" "F.Paste")
			(net "M_C_CPU1_SB_DQS_DN<2>")
		)
		(pad "CU58" smd circle
			(at 18.18005 27.090116 180)
			(size 0.450088 0.450088)
			(layers "F.Cu" "F.Mask" "F.Paste")
			(net "GND")
		)
		(pad "CU59" smd circle
			(at 19.120104 27.090116 180)
			(size 0.450088 0.450088)
			(layers "F.Cu" "F.Mask" "F.Paste")
			(net "M_D_CPU1_SB_DQS_DN<7>")
		)
		(pad "CU60" smd circle
			(at 20.059904 27.090116 180)
			(size 0.450088 0.450088)
			(layers "F.Cu" "F.Mask" "F.Paste")
			(net "M_D_CPU1_SB_DQS_DN<2>")
		)
		(pad "CU61" smd circle
			(at 20.999958 27.090116 180)
			(size 0.450088 0.450088)
			(layers "F.Cu" "F.Mask" "F.Paste")
			(net "GND")
		)
		(pad "CU62" smd circle
			(at 21.940012 27.090116 180)
			(size 0.450088 0.450088)
			(layers "F.Cu" "F.Mask" "F.Paste")
			(net "M_B_CPU1_SB_DQS_DN<7>")
		)
		(pad "CU63" smd circle
			(at 22.880066 27.090116 180)
			(size 0.450088 0.450088)
			(layers "F.Cu" "F.Mask" "F.Paste")
			(net "GND")
		)
		(pad "CU64" smd circle
			(at 23.82012 27.090116 180)
			(size 0.450088 0.450088)
			(layers "F.Cu" "F.Mask" "F.Paste")
			(net "M_B_CPU1_SB_DQS_DN<2>")
		)
		(pad "CU65" smd circle
			(at 24.75992 27.090116 180)
			(size 0.450088 0.450088)
			(layers "F.Cu" "F.Mask" "F.Paste")
			(net "GND")
		)
		(pad "CU66" smd circle
			(at 25.699974 27.090116 180)
			(size 0.450088 0.450088)
			(layers "F.Cu" "F.Mask" "F.Paste")
			(net "M_F_CPU1_SB_DQS_DN<7>")
		)
		(pad "CU67" smd circle
			(at 26.640028 27.090116 180)
			(size 0.450088 0.450088)
			(layers "F.Cu" "F.Mask" "F.Paste")
			(net "M_F_CPU1_SB_DQS_DN<2>")
		)
		(pad "CU68" smd circle
			(at 27.580082 27.090116 180)
			(size 0.450088 0.450088)
			(layers "F.Cu" "F.Mask" "F.Paste")
			(net "GND")
		)
		(pad "CU69" smd circle
			(at 28.519882 27.090116 180)
			(size 0.450088 0.450088)
			(layers "F.Cu" "F.Mask" "F.Paste")
			(net "M_E_CPU1_SB_DQS_DN<7>")
		)
		(pad "CU70" smd circle
			(at 29.459936 27.090116 180)
			(size 0.450088 0.450088)
			(layers "F.Cu" "F.Mask" "F.Paste")
			(net "GND")
		)
		(pad "CU71" smd circle
			(at 30.39999 27.090116 180)
			(size 0.450088 0.450088)
			(layers "F.Cu" "F.Mask" "F.Paste")
			(net "M_E_CPU1_SB_DQS_DN<2>")
		)
		(pad "CU72" smd circle
			(at 31.340044 27.090116 180)
			(size 0.450088 0.450088)
			(layers "F.Cu" "F.Mask" "F.Paste")
			(net "GND")
		)
		(pad "CU73" smd circle
			(at 32.280098 27.090116 180)
			(size 0.450088 0.450088)
			(layers "F.Cu" "F.Mask" "F.Paste")
			(net "M_A_CPU1_SB_DQS_DN<7>")
		)
		(pad "CU74" smd circle
			(at 33.219898 27.090116 180)
			(size 0.450088 0.450088)
			(layers "F.Cu" "F.Mask" "F.Paste")
			(net "M_A_CPU1_SB_DQS_DN<2>")
		)
		(pad "CU75" smd circle
			(at 34.159952 27.090116 180)
			(size 0.450088 0.450088)
			(layers "F.Cu" "F.Mask" "F.Paste")
			(net "GND")
		)
		(pad "CV2" smd circle
			(at -33.990026 27.900122 180)
			(size 0.450088 0.450088)
			(layers "F.Cu" "F.Mask" "F.Paste")
			(net "M_G_CPU1_SB_DQ<20>")
		)
		(pad "CV3" smd circle
			(at -33.049972 27.900122 180)
			(size 0.450088 0.450088)
			(layers "F.Cu" "F.Mask" "F.Paste")
			(net "GND")
		)
		(pad "CV4" smd circle
			(at -32.109918 27.900122 180)
			(size 0.450088 0.450088)
			(layers "F.Cu" "F.Mask" "F.Paste")
			(net "M_G_CPU1_SB_DQS_DP<7>")
		)
		(pad "CV5" smd circle
			(at -31.170118 27.900122 180)
			(size 0.450088 0.450088)
			(layers "F.Cu" "F.Mask" "F.Paste")
			(net "GND")
		)
		(pad "CV6" smd circle
			(at -30.230064 27.900122 180)
			(size 0.450088 0.450088)
			(layers "F.Cu" "F.Mask" "F.Paste")
			(net "M_K_CPU1_SB_DQ<20>")
		)
		(pad "CV7" smd circle
			(at -29.29001 27.900122 180)
			(size 0.450088 0.450088)
			(layers "F.Cu" "F.Mask" "F.Paste")
			(net "M_K_CPU1_SB_DQS_DP<7>")
		)
		(pad "CV8" smd circle
			(at -28.349956 27.900122 180)
			(size 0.450088 0.450088)
			(layers "F.Cu" "F.Mask" "F.Paste")
			(net "GND")
		)
		(pad "CV9" smd circle
			(at -27.409902 27.900122 180)
			(size 0.450088 0.450088)
			(layers "F.Cu" "F.Mask" "F.Paste")
			(net "M_L_CPU1_SB_DQ<20>")
		)
		(pad "CV10" smd circle
			(at -26.470102 27.900122 180)
			(size 0.450088 0.450088)
			(layers "F.Cu" "F.Mask" "F.Paste")
			(net "GND")
		)
		(pad "CV11" smd circle
			(at -25.530048 27.900122 180)
			(size 0.450088 0.450088)
			(layers "F.Cu" "F.Mask" "F.Paste")
			(net "M_L_CPU1_SB_DQS_DP<7>")
		)
		(pad "CV12" smd circle
			(at -24.589994 27.900122 180)
			(size 0.450088 0.450088)
			(layers "F.Cu" "F.Mask" "F.Paste")
			(net "GND")
		)
		(pad "CV13" smd circle
			(at -23.64994 27.900122 180)
			(size 0.450088 0.450088)
			(layers "F.Cu" "F.Mask" "F.Paste")
			(net "M_H_CPU1_SB_DQ<20>")
		)
		(pad "CV14" smd circle
			(at -22.709886 27.900122 180)
			(size 0.450088 0.450088)
			(layers "F.Cu" "F.Mask" "F.Paste")
			(net "M_H_CPU1_SB_DQS_DP<7>")
		)
		(pad "CV15" smd circle
			(at -21.770086 27.900122 180)
			(size 0.450088 0.450088)
			(layers "F.Cu" "F.Mask" "F.Paste")
			(net "GND")
		)
		(pad "CV16" smd circle
			(at -20.830032 27.900122 180)
			(size 0.450088 0.450088)
			(layers "F.Cu" "F.Mask" "F.Paste")
			(net "M_J_CPU1_SB_DQ<20>")
		)
		(pad "CV17" smd circle
			(at -19.889978 27.900122 180)
			(size 0.450088 0.450088)
			(layers "F.Cu" "F.Mask" "F.Paste")
			(net "GND")
		)
		(pad "CV18" smd circle
			(at -18.949924 27.900122 180)
			(size 0.450088 0.450088)
			(layers "F.Cu" "F.Mask" "F.Paste")
			(net "M_J_CPU1_SB_DQS_DP<7>")
		)
		(pad "CV19" smd circle
			(at -18.010124 27.900122 180)
			(size 0.450088 0.450088)
			(layers "F.Cu" "F.Mask" "F.Paste")
			(net "GND")
		)
		(pad "CV20" smd circle
			(at -17.07007 27.900122 180)
			(size 0.450088 0.450088)
			(layers "F.Cu" "F.Mask" "F.Paste")
			(net "M_I_CPU1_SB_DQ<20>")
		)
		(pad "CV21" smd circle
			(at -16.130016 27.900122 180)
			(size 0.450088 0.450088)
			(layers "F.Cu" "F.Mask" "F.Paste")
			(net "M_I_CPU1_SB_DQS_DP<7>")
		)
		(pad "CV22" smd circle
			(at -15.189962 27.900122 180)
			(size 0.450088 0.450088)
			(layers "F.Cu" "F.Mask" "F.Paste")
			(net "GND")
		)
		(pad "CV23" smd circle
			(at -14.249908 27.900122 180)
			(size 0.450088 0.450088)
			(layers "F.Cu" "F.Mask" "F.Paste")
			(net "PVDDCR_CPU1_P1")
		)
		(pad "CV24" smd circle
			(at -13.310108 27.900122 180)
			(size 0.450088 0.450088)
			(layers "F.Cu" "F.Mask" "F.Paste")
			(net "PVDDCR_CPU1_P1")
		)
		(pad "CV25" smd circle
			(at -12.370054 27.900122 180)
			(size 0.450088 0.450088)
			(layers "F.Cu" "F.Mask" "F.Paste")
			(net "GND")
		)
		(pad "CV26" smd circle
			(at -11.43 27.900122 180)
			(size 0.450088 0.450088)
			(layers "F.Cu" "F.Mask" "F.Paste")
			(net "PVDDCR_CPU1_P1")
		)
		(pad "CV27" smd circle
			(at -10.489946 27.900122 180)
			(size 0.450088 0.450088)
			(layers "F.Cu" "F.Mask" "F.Paste")
			(net "PVDDCR_CPU1_P1")
		)
		(pad "CV28" smd circle
			(at -9.549892 27.900122 180)
			(size 0.450088 0.450088)
			(layers "F.Cu" "F.Mask" "F.Paste")
			(net "GND")
		)
		(pad "CV29" smd circle
			(at -8.610092 27.900122 180)
			(size 0.450088 0.450088)
			(layers "F.Cu" "F.Mask" "F.Paste")
			(net "PVDDCR_CPU1_P1")
		)
		(pad "CV30" smd circle
			(at -7.670038 27.900122 180)
			(size 0.450088 0.450088)
			(layers "F.Cu" "F.Mask" "F.Paste")
			(net "PVDDCR_CPU1_P1")
		)
		(pad "CV31" smd circle
			(at -6.729984 27.900122 180)
			(size 0.450088 0.450088)
			(layers "F.Cu" "F.Mask" "F.Paste")
			(net "GND")
		)
		(pad "CV32" smd circle
			(at -5.78993 27.900122 180)
			(size 0.450088 0.450088)
			(layers "F.Cu" "F.Mask" "F.Paste")
			(net "PVDDCR_CPU1_P1")
		)
		(pad "CV33" smd circle
			(at -4.849876 27.900122 180)
			(size 0.450088 0.450088)
			(layers "F.Cu" "F.Mask" "F.Paste")
			(net "PVDDCR_CPU1_P1")
		)
		(pad "CV34" smd circle
			(at -3.910076 27.900122 180)
			(size 0.450088 0.450088)
			(layers "F.Cu" "F.Mask" "F.Paste")
			(net "GND")
		)
		(pad "CV35" smd circle
			(at -2.970022 27.900122 180)
			(size 0.450088 0.450088)
			(layers "F.Cu" "F.Mask" "F.Paste")
			(net "P5E_CPU1_P3_RX_DP<0>")
		)
		(pad "CV36" smd circle
			(at -2.029968 27.900122 180)
			(size 0.450088 0.450088)
			(layers "F.Cu" "F.Mask" "F.Paste")
			(net "P5E_CPU1_P3_RX_DN<0>")
		)
		(pad "CV37" smd circle
			(at -1.089914 27.900122 180)
			(size 0.450088 0.450088)
			(layers "F.Cu" "F.Mask" "F.Paste")
			(net "GND")
		)
		(pad "CV39" smd circle
			(at 0.78994 27.900122 180)
			(size 0.450088 0.450088)
			(layers "F.Cu" "F.Mask" "F.Paste")
			(net "GND")
		)
		(pad "CV40" smd circle
			(at 1.729994 27.900122 180)
			(size 0.450088 0.450088)
			(layers "F.Cu" "F.Mask" "F.Paste")
			(net "P5E_CPU1_P1_TX_DN<15>")
		)
		(pad "CV41" smd circle
			(at 2.670048 27.900122 180)
			(size 0.450088 0.450088)
			(layers "F.Cu" "F.Mask" "F.Paste")
			(net "P5E_CPU1_P1_TX_DP<15>")
		)
		(pad "CV42" smd circle
			(at 3.610102 27.900122 180)
			(size 0.450088 0.450088)
			(layers "F.Cu" "F.Mask" "F.Paste")
			(net "GND")
		)
		(pad "CV43" smd circle
			(at 4.549902 27.900122 180)
			(size 0.450088 0.450088)
			(layers "F.Cu" "F.Mask" "F.Paste")
			(net "PVDDCR_CPU1_P1")
		)
		(pad "CV44" smd circle
			(at 5.489956 27.900122 180)
			(size 0.450088 0.450088)
			(layers "F.Cu" "F.Mask" "F.Paste")
			(net "PVDDCR_CPU1_P1")
		)
		(pad "CV45" smd circle
			(at 6.43001 27.900122 180)
			(size 0.450088 0.450088)
			(layers "F.Cu" "F.Mask" "F.Paste")
			(net "GND")
		)
		(pad "CV46" smd circle
			(at 7.370064 27.900122 180)
			(size 0.450088 0.450088)
			(layers "F.Cu" "F.Mask" "F.Paste")
			(net "PVDDCR_CPU1_P1")
		)
		(pad "CV47" smd circle
			(at 8.310118 27.900122 180)
			(size 0.450088 0.450088)
			(layers "F.Cu" "F.Mask" "F.Paste")
			(net "PVDDCR_CPU1_P1")
		)
		(pad "CV48" smd circle
			(at 9.249918 27.900122 180)
			(size 0.450088 0.450088)
			(layers "F.Cu" "F.Mask" "F.Paste")
			(net "GND")
		)
		(pad "CV49" smd circle
			(at 10.189972 27.900122 180)
			(size 0.450088 0.450088)
			(layers "F.Cu" "F.Mask" "F.Paste")
			(net "PVDDCR_CPU1_P1")
		)
		(pad "CV50" smd circle
			(at 11.130026 27.900122 180)
			(size 0.450088 0.450088)
			(layers "F.Cu" "F.Mask" "F.Paste")
			(net "PVDDCR_CPU1_P1")
		)
		(pad "CV51" smd circle
			(at 12.07008 27.900122 180)
			(size 0.450088 0.450088)
			(layers "F.Cu" "F.Mask" "F.Paste")
			(net "GND")
		)
		(pad "CV52" smd circle
			(at 13.00988 27.900122 180)
			(size 0.450088 0.450088)
			(layers "F.Cu" "F.Mask" "F.Paste")
			(net "PVDDCR_CPU1_P1")
		)
		(pad "CV53" smd circle
			(at 13.949934 27.900122 180)
			(size 0.450088 0.450088)
			(layers "F.Cu" "F.Mask" "F.Paste")
			(net "PVDDCR_CPU1_P1")
		)
		(pad "CV54" smd circle
			(at 14.889988 27.900122 180)
			(size 0.450088 0.450088)
			(layers "F.Cu" "F.Mask" "F.Paste")
			(net "GND")
		)
		(pad "CV55" smd circle
			(at 15.830042 27.900122 180)
			(size 0.450088 0.450088)
			(layers "F.Cu" "F.Mask" "F.Paste")
			(net "M_C_CPU1_SB_DQS_DP<7>")
		)
		(pad "CV56" smd circle
			(at 16.770096 27.900122 180)
			(size 0.450088 0.450088)
			(layers "F.Cu" "F.Mask" "F.Paste")
			(net "M_C_CPU1_SB_DQ<20>")
		)
		(pad "CV57" smd circle
			(at 17.709896 27.900122 180)
			(size 0.450088 0.450088)
			(layers "F.Cu" "F.Mask" "F.Paste")
			(net "GND")
		)
		(pad "CV58" smd circle
			(at 18.64995 27.900122 180)
			(size 0.450088 0.450088)
			(layers "F.Cu" "F.Mask" "F.Paste")
			(net "M_D_CPU1_SB_DQS_DP<7>")
		)
		(pad "CV59" smd circle
			(at 19.590004 27.900122 180)
			(size 0.450088 0.450088)
			(layers "F.Cu" "F.Mask" "F.Paste")
			(net "GND")
		)
		(pad "CV60" smd circle
			(at 20.530058 27.900122 180)
			(size 0.450088 0.450088)
			(layers "F.Cu" "F.Mask" "F.Paste")
			(net "M_D_CPU1_SB_DQ<20>")
		)
		(pad "CV61" smd circle
			(at 21.470112 27.900122 180)
			(size 0.450088 0.450088)
			(layers "F.Cu" "F.Mask" "F.Paste")
			(net "GND")
		)
		(pad "CV62" smd circle
			(at 22.409912 27.900122 180)
			(size 0.450088 0.450088)
			(layers "F.Cu" "F.Mask" "F.Paste")
			(net "M_B_CPU1_SB_DQS_DP<7>")
		)
		(pad "CV63" smd circle
			(at 23.349966 27.900122 180)
			(size 0.450088 0.450088)
			(layers "F.Cu" "F.Mask" "F.Paste")
			(net "M_B_CPU1_SB_DQ<20>")
		)
		(pad "CV64" smd circle
			(at 24.29002 27.900122 180)
			(size 0.450088 0.450088)
			(layers "F.Cu" "F.Mask" "F.Paste")
			(net "GND")
		)
		(pad "CV65" smd circle
			(at 25.230074 27.900122 180)
			(size 0.450088 0.450088)
			(layers "F.Cu" "F.Mask" "F.Paste")
			(net "M_F_CPU1_SB_DQS_DP<7>")
		)
		(pad "CV66" smd circle
			(at 26.170128 27.900122 180)
			(size 0.450088 0.450088)
			(layers "F.Cu" "F.Mask" "F.Paste")
			(net "GND")
		)
		(pad "CV67" smd circle
			(at 27.109928 27.900122 180)
			(size 0.450088 0.450088)
			(layers "F.Cu" "F.Mask" "F.Paste")
			(net "M_F_CPU1_SB_DQ<20>")
		)
		(pad "CV68" smd circle
			(at 28.049982 27.900122 180)
			(size 0.450088 0.450088)
			(layers "F.Cu" "F.Mask" "F.Paste")
			(net "GND")
		)
		(pad "CV69" smd circle
			(at 28.990036 27.900122 180)
			(size 0.450088 0.450088)
			(layers "F.Cu" "F.Mask" "F.Paste")
			(net "M_E_CPU1_SB_DQS_DP<7>")
		)
		(pad "CV70" smd circle
			(at 29.93009 27.900122 180)
			(size 0.450088 0.450088)
			(layers "F.Cu" "F.Mask" "F.Paste")
			(net "M_E_CPU1_SB_DQ<20>")
		)
		(pad "CV71" smd circle
			(at 30.86989 27.900122 180)
			(size 0.450088 0.450088)
			(layers "F.Cu" "F.Mask" "F.Paste")
			(net "GND")
		)
		(pad "CV72" smd circle
			(at 31.809944 27.900122 180)
			(size 0.450088 0.450088)
			(layers "F.Cu" "F.Mask" "F.Paste")
			(net "M_A_CPU1_SB_DQS_DP<7>")
		)
		(pad "CV73" smd circle
			(at 32.749998 27.900122 180)
			(size 0.450088 0.450088)
			(layers "F.Cu" "F.Mask" "F.Paste")
			(net "GND")
		)
		(pad "CV74" smd circle
			(at 33.690052 27.900122 180)
			(size 0.450088 0.450088)
			(layers "F.Cu" "F.Mask" "F.Paste")
			(net "M_A_CPU1_SB_DQ<20>")
		)
		(pad "CW1" smd circle
			(at -34.459926 28.710128 180)
			(size 0.450088 0.450088)
			(layers "F.Cu" "F.Mask" "F.Paste")
			(net "GND")
		)
		(pad "CW2" smd circle
			(at -33.519872 28.710128 180)
			(size 0.450088 0.450088)
			(layers "F.Cu" "F.Mask" "F.Paste")
			(net "M_G_CPU1_SB_DQ<22>")
		)
		(pad "CW3" smd circle
			(at -32.580072 28.710128 180)
			(size 0.450088 0.450088)
			(layers "F.Cu" "F.Mask" "F.Paste")
			(net "M_G_CPU1_SB_DQ<21>")
		)
		(pad "CW4" smd circle
			(at -31.640018 28.710128 180)
			(size 0.450088 0.450088)
			(layers "F.Cu" "F.Mask" "F.Paste")
			(net "PVDD11_S3_P1")
		)
		(pad "CW5" smd circle
			(at -30.699964 28.710128 180)
			(size 0.450088 0.450088)
			(layers "F.Cu" "F.Mask" "F.Paste")
			(net "M_K_CPU1_SB_DQ<22>")
		)
		(pad "CW6" smd circle
			(at -29.75991 28.710128 180)
			(size 0.450088 0.450088)
			(layers "F.Cu" "F.Mask" "F.Paste")
			(net "GND")
		)
		(pad "CW7" smd circle
			(at -28.82011 28.710128 180)
			(size 0.450088 0.450088)
			(layers "F.Cu" "F.Mask" "F.Paste")
			(net "M_K_CPU1_SB_DQ<21>")
		)
		(pad "CW8" smd circle
			(at -27.880056 28.710128 180)
			(size 0.450088 0.450088)
			(layers "F.Cu" "F.Mask" "F.Paste")
			(net "GND")
		)
	)
)
